FILE_TYPE = CONNECTIVITY;
{Allegro Design Entry HDL 17.2-2016 S081 (4005846) 1/11/2022}
"PAGE_NUMBER" = 17;
0"NC";
1"M_H_CPU0_SA_DQ<31:0>";
2"M_H_CPU0_SB_DQ<31:0>";
3"M_H_CPU0_SA_CB<7:0>";
4"M_H_CPU0_SB_CB<7:0>";
5"M_H_CPU0_SA_DQS_DP<9:0>";
6"M_H_CPU0_SB_DQS_DP<9:0>";
7"M_H_CPU0_SA_CA<6:0>";
8"M_H_CPU0_SB_CA<6:0>";
9"M_H_CPU0_SA_DQS_DN<9:0>";
10"M_H_CPU0_SB_DQS_DN<9:0>";
11"M_H_CPU0_ALERT_N";
12"TP_M_H_CPU0_SA_TEST39H";
13"M_H_CPU0_ALERT_R_N";
14"M_H_CPU0_CLK_DP<0>";
15"M_H_CPU0_CLK_DN<0>";
16"M_H_CPU0_SA_CS_N<0>";
17"M_H_CPU0_SA_CS_N<1>";
18"M_H_CPU0_SA_RSP<0>";
19"M_H_CPU0_SA_PAR";
20"M_H_CPU0_SB_CS_N<1>";
21"M_H_CPU0_SB_CS_N<0>";
22"M_H_CPU0_SB_RSP<0>";
23"M_H_CPU0_SB_PAR";
24"M_H_CPU0_RESET_N";
25"M_H_CPU0_SB_DQS_DP<9>";
26"M_H_CPU0_SB_DQS_DN<9>";
27"M_H_CPU0_SB_DQS_DN<8>";
28"M_H_CPU0_SB_CA<6>";
29"M_H_CPU0_SA_CA<6>";
30"M_H_CPU0_SB_CA<5>";
31"M_H_CPU0_SA_CA<5>";
32"M_H_CPU0_SB_CA<4>";
33"M_H_CPU0_SA_CA<4>";
34"M_H_CPU0_SB_CA<3>";
35"M_H_CPU0_SA_CA<3>";
36"M_H_CPU0_SB_CA<2>";
37"M_H_CPU0_SA_CA<2>";
38"M_H_CPU0_SB_CA<1>";
39"M_H_CPU0_SA_CA<1>";
40"M_H_CPU0_SB_CA<0>";
41"M_H_CPU0_SA_CA<0>";
42"M_H_CPU0_SB_DQS_DP<8>";
43"M_H_CPU0_SB_DQS_DP<7>";
44"M_H_CPU0_SB_DQS_DP<6>";
45"M_H_CPU0_SB_DQS_DP<5>";
46"M_H_CPU0_SB_DQS_DP<4>";
47"M_H_CPU0_SA_DQS_DP<9>";
48"M_H_CPU0_SB_DQS_DP<3>";
49"M_H_CPU0_SB_DQS_DN<7>";
50"M_H_CPU0_SB_DQS_DP<2>";
51"M_H_CPU0_SB_DQS_DN<6>";
52"M_H_CPU0_SB_DQS_DP<1>";
53"M_H_CPU0_SB_DQS_DN<5>";
54"M_H_CPU0_SB_DQS_DP<0>";
55"M_H_CPU0_SB_DQS_DN<4>";
56"M_H_CPU0_SA_DQS_DN<9>";
57"M_H_CPU0_SB_DQS_DN<3>";
58"M_H_CPU0_SB_DQS_DN<2>";
59"M_H_CPU0_SB_DQS_DN<1>";
60"M_H_CPU0_SB_DQS_DN<0>";
61"M_H_CPU0_SA_DQS_DN<1>";
62"M_H_CPU0_SA_DQS_DN<0>";
63"M_H_CPU0_SA_DQS_DP<8>";
64"M_H_CPU0_SA_DQS_DP<7>";
65"M_H_CPU0_SA_DQS_DP<6>";
66"M_H_CPU0_SA_DQS_DP<5>";
67"M_H_CPU0_SA_DQS_DP<4>";
68"M_H_CPU0_SA_DQS_DN<8>";
69"M_H_CPU0_SA_DQS_DP<3>";
70"M_H_CPU0_SA_DQS_DN<7>";
71"M_H_CPU0_SA_DQS_DP<2>";
72"M_H_CPU0_SA_DQS_DN<6>";
73"M_H_CPU0_SA_DQS_DP<1>";
74"M_H_CPU0_SA_DQS_DN<5>";
75"M_H_CPU0_SA_DQS_DP<0>";
76"M_H_CPU0_SA_DQS_DN<4>";
77"M_H_CPU0_SA_DQS_DN<3>";
78"M_H_CPU0_SA_DQS_DN<2>";
79"M_H_CPU0_SB_CB<7>";
80"M_H_CPU0_SB_CB<6>";
81"M_H_CPU0_SB_CB<5>";
82"M_H_CPU0_SB_CB<4>";
83"M_H_CPU0_SB_CB<3>";
84"M_H_CPU0_SB_CB<2>";
85"M_H_CPU0_SA_CB<7>";
86"M_H_CPU0_SB_CB<1>";
87"M_H_CPU0_SB_CB<0>";
88"M_H_CPU0_SA_CB<5>";
89"M_H_CPU0_SB_DQ<30>";
90"M_H_CPU0_SA_CB<4>";
91"M_H_CPU0_SA_CB<3>";
92"M_H_CPU0_SA_CB<2>";
93"M_H_CPU0_SA_CB<1>";
94"M_H_CPU0_SA_CB<0>";
95"M_H_CPU0_SB_DQ<29>";
96"M_H_CPU0_SB_DQ<28>";
97"M_H_CPU0_SB_DQ<27>";
98"M_H_CPU0_SB_DQ<26>";
99"M_H_CPU0_SB_DQ<25>";
100"M_H_CPU0_SB_DQ<24>";
101"M_H_CPU0_SB_DQ<23>";
102"M_H_CPU0_SB_DQ<22>";
103"M_H_CPU0_SB_DQ<21>";
104"M_H_CPU0_SA_CB<6>";
105"M_H_CPU0_SB_DQ<31>";
106"M_H_CPU0_SB_DQ<9>";
107"M_H_CPU0_SB_DQ<8>";
108"M_H_CPU0_SB_DQ<7>";
109"M_H_CPU0_SB_DQ<6>";
110"M_H_CPU0_SB_DQ<5>";
111"M_H_CPU0_SB_DQ<19>";
112"M_H_CPU0_SB_DQ<4>";
113"M_H_CPU0_SB_DQ<18>";
114"M_H_CPU0_SB_DQ<3>";
115"M_H_CPU0_SB_DQ<17>";
116"M_H_CPU0_SB_DQ<2>";
117"M_H_CPU0_SB_DQ<16>";
118"M_H_CPU0_SB_DQ<15>";
119"M_H_CPU0_SB_DQ<14>";
120"M_H_CPU0_SB_DQ<13>";
121"M_H_CPU0_SB_DQ<12>";
122"M_H_CPU0_SB_DQ<11>";
123"M_H_CPU0_SB_DQ<10>";
124"M_H_CPU0_SB_DQ<20>";
125"M_H_CPU0_SA_DQ<25>";
126"M_H_CPU0_SA_DQ<24>";
127"M_H_CPU0_SA_DQ<23>";
128"M_H_CPU0_SA_DQ<22>";
129"M_H_CPU0_SA_DQ<21>";
130"M_H_CPU0_SA_DQ<20>";
131"M_H_CPU0_SA_DQ<31>";
132"M_H_CPU0_SA_DQ<30>";
133"M_H_CPU0_SB_DQ<1>";
134"M_H_CPU0_SB_DQ<0>";
135"M_H_CPU0_SA_DQ<19>";
136"M_H_CPU0_SA_DQ<18>";
137"M_H_CPU0_SA_DQ<29>";
138"M_H_CPU0_SA_DQ<17>";
139"M_H_CPU0_SA_DQ<28>";
140"M_H_CPU0_SA_DQ<16>";
141"M_H_CPU0_SA_DQ<27>";
142"M_H_CPU0_SA_DQ<26>";
143"M_H_CPU0_SA_DQ<14>";
144"M_H_CPU0_SA_DQ<13>";
145"M_H_CPU0_SA_DQ<9>";
146"M_H_CPU0_SA_DQ<12>";
147"M_H_CPU0_SA_DQ<8>";
148"M_H_CPU0_SA_DQ<11>";
149"M_H_CPU0_SA_DQ<7>";
150"M_H_CPU0_SA_DQ<10>";
151"M_H_CPU0_SA_DQ<6>";
152"M_H_CPU0_SA_DQ<5>";
153"M_H_CPU0_SA_DQ<4>";
154"M_H_CPU0_SA_DQ<3>";
155"M_H_CPU0_SA_DQ<2>";
156"M_H_CPU0_SA_DQ<1>";
157"M_H_CPU0_SA_DQ<0>";
158"M_H_CPU0_SA_DQ<15>";
%"GENOA_SP5"
"8","(-4600,3600)","0","pure_quanta","I159";
;
LOCATION"U25"
$SEC"8"
CDS_SEC"8"
PART_TYPE"SMLF"
MATERIAL"IO"
VALUE"SOCKET6096_13568-001"
PART_NUMBER"DGA^6000030"
CDS_LIB"pure_quanta"
CDS_LMAN_SYM_OUTLINE"-650,2525,650,-2525"
NEEDS_NO_SIZE"TRUE";
"TEST39H"
$PN"BF14"12;
"MH1_CLK_L"
$PN"BG12"0;
"MH1_CLK_H"
$PN"BF13"0;
"MH0_CLK_L"
$PN"BD13"15;
"MH0_CLK_H"
$PN"BC12"14;
"MHB_PAR"
$PN"BL14"23;
"MHA_PAR"
$PN"BC14"19;
"MHB_DQS_H9"
$PN"BV13"25;
"MHA_CHECK5"
$PN"AP14"88;
"MHA_DATA14"
$PN"T13"143;
"MHA_DATA25"
$PN"AD14"125;
"MHA_DQS_L1"
$PN"P13"61;
"MHB0_CS_L1"
$PN"BN12"20;
"MHB1_CS_L0"
$PN"BL12"0;
"MHB_DATA30"
$PN"DE12"89;
"MHB_DQS_H8"
$PN"DD14"42;
"MHA_CHECK4"
$PN"AN12"90;
"MHA_DATA13"
$PN"T14"144;
"MHA_DATA24"
$PN"AC12"126;
"MHA_DQS_L0"
$PN"H13"62;
"MHB0_CS_L0"
$PN"BM14"21;
"MHB_DQS_H7"
$PN"CV14"43;
"MHA_CHECK3"
$PN"AL14"91;
"MHA_DATA9"
$PN"M14"145;
"MHA_DATA12"
$PN"R12"146;
"MHA_DATA23"
$PN"AC14"127;
"MHB_DATA9"
$PN"CJ14"106;
"MHB_DQS_H6"
$PN"CM14"44;
"MHA_CHECK2"
$PN"AK13"92;
"MHA_DATA8"
$PN"L12"147;
"MHA_DATA11"
$PN"N14"148;
"MHA_DATA22"
$PN"AB13"128;
"MHB_DATA8"
$PN"CH13"107;
"MHB_DQS_H5"
$PN"CF14"45;
"MHB_DQS_L9"
$PN"BW12"26;
"MHA_CHECK1"
$PN"AK14"93;
"MHA_DATA7"
$PN"L14"149;
"MHA_DATA10"
$PN"M13"150;
"MHA_DATA21"
$PN"AB14"129;
"MHB_DATA7"
$PN"CH14"108;
"MHB_DQS_H4"
$PN"BY14"46;
"MHB_DQS_L8"
$PN"DC14"27;
"MHA1_CS_L1"
$PN"AW14"0;
"MHA_CHECK0"
$PN"AJ12"94;
"MHA_DATA6"
$PN"K13"151;
"MHA_DATA20"
$PN"AA12"130;
"MHA_DATA31"
$PN"AJ14"131;
"MHA_DQS_H9"
$PN"AN14"47;
"MHB_DATA6"
$PN"CG12"109;
"MHB_DQS_H3"
$PN"DB13"48;
"MHB_DQS_L7"
$PN"CU14"49;
"MHA0_CS_L1"
$PN"AV14"17;
"MHA1_CS_L0"
$PN"AV13"0;
"MHA_DATA5"
$PN"K14"152;
"MHA_DATA30"
$PN"AH13"132;
"MHA_DQS_H8"
$PN"AG14"63;
"MHB_DATA5"
$PN"CG14"110;
"MHB_DATA19"
$PN"CT14"111;
"MHB_DQS_H2"
$PN"CT13"50;
"MHB_DQS_L6"
$PN"CL14"51;
"MHA0_CS_L0"
$PN"AU12"16;
"MHA_DATA4"
$PN"J12"153;
"MHA_DQS_H7"
$PN"AA14"64;
"MHB_CA6"
$PN"BK13"28;
"MHB_DATA4"
$PN"CF13"112;
"MHB_DATA18"
$PN"CR12"113;
"MHB_DATA29"
$PN"DE14"95;
"MHB_DQS_H1"
$PN"CK13"52;
"MHB_DQS_L5"
$PN"CE14"53;
"MHA_CA6"
$PN"BB14"29;
"MHA_DATA3"
$PN"G14"154;
"MHA_DQS_H6"
$PN"R14"65;
"MHB1_RSP_L"
$PN"BR12"0;
"MHB_CA5"
$PN"BK14"30;
"MHB_DATA3"
$PN"CD14"114;
"MHB_DATA17"
$PN"CR14"115;
"MHB_DATA28"
$PN"DD13"96;
"MHB_DQS_H0"
$PN"CD13"54;
"MHB_DQS_L4"
$PN"BW14"55;
"MHA_CA5"
$PN"BB13"31;
"MHA_DATA2"
$PN"F13"155;
"MHA_DQS_H5"
$PN"J14"66;
"MHA_DQS_L9"
$PN"AM14"56;
"MHB0_RSP_L"
$PN"BP13"22;
"MHB_CA4"
$PN"BJ14"32;
"MHB_CHECK7"
$PN"BV14"79;
"MHB_DATA2"
$PN"CC12"116;
"MHB_DATA16"
$PN"CP13"117;
"MHB_DATA27"
$PN"DB14"97;
"MHB_DQS_L3"
$PN"DC12"57;
"MHA_CA4"
$PN"BA12"33;
"MHA_DATA1"
$PN"F14"156;
"MHA_DQS_H4"
$PN"AL12"67;
"MHA_DQS_L8"
$PN"AF14"68;
"MHB_CA3"
$PN"BJ12"34;
"MHB_CHECK6"
$PN"BU12"80;
"MHB_DATA1"
$PN"CC14"133;
"MHB_DATA15"
$PN"CP14"118;
"MHB_DATA26"
$PN"DA12"98;
"MHB_DQS_L2"
$PN"CU12"58;
"MHA_CA3"
$PN"BA14"35;
"MHA_DATA0"
$PN"E12"157;
"MHA_DQS_H3"
$PN"AE12"69;
"MHA_DQS_L7"
$PN"Y14"70;
"MHB_CA2"
$PN"BH13"36;
"MHB_CHECK5"
$PN"BU14"81;
"MHB_DATA0"
$PN"CB13"134;
"MHB_DATA14"
$PN"CN12"119;
"MHB_DATA25"
$PN"DA14"99;
"MHB_DQS_L1"
$PN"CL12"59;
"MHA_CA2"
$PN"AY14"37;
"MHA_DATA19"
$PN"W14"135;
"MHA_DQS_H2"
$PN"W12"71;
"MHA_DQS_L6"
$PN"P14"72;
"MHB_CA1"
$PN"BH14"38;
"MHB_CHECK4"
$PN"BT13"82;
"MHB_DATA13"
$PN"CN14"120;
"MHB_DATA24"
$PN"CY13"100;
"MHB_DQS_L0"
$PN"CE12"60;
"MHA_CA1"
$PN"AY13"39;
"MHA_DATA18"
$PN"V13"136;
"MHA_DATA29"
$PN"AH14"137;
"MHA_DQS_H1"
$PN"N12"73;
"MHA_DQS_L5"
$PN"H14"74;
"MHB_CA0"
$PN"BG14"40;
"MHB_CHECK3"
$PN"CB14"83;
"MHB_DATA12"
$PN"CM13"121;
"MHB_DATA23"
$PN"CY14"101;
"MHA1_RSP_L"
$PN"BP14"0;
"MHA_CA0"
$PN"AW12"41;
"MHA_DATA17"
$PN"V14"138;
"MHA_DATA28"
$PN"AG12"139;
"MHA_DQS_H0"
$PN"G12"75;
"MHA_DQS_L4"
$PN"AM13"76;
"MHB_CHECK2"
$PN"CA12"84;
"MHB_DATA11"
$PN"CK14"122;
"MHB_DATA22"
$PN"CW12"102;
"MHA0_RSP_L"
$PN"BN14"18;
"MHA_CHECK7"
$PN"AR14"85;
"MHA_DATA16"
$PN"U12"140;
"MHA_DATA27"
$PN"AE14"141;
"MHA_DQS_L3"
$PN"AF13"77;
"MHB_CHECK1"
$PN"CA14"86;
"MHB_DATA10"
$PN"CJ12"123;
"MHB_DATA21"
$PN"CW14"103;
"MHA_CHECK6"
$PN"AP13"104;
"MHA_DATA15"
$PN"U14"158;
"MHA_DATA26"
$PN"AD13"142;
"MHA_DQS_L2"
$PN"Y13"78;
"MHB1_CS_L1"
$PN"BM13"0;
"MHB_CHECK0"
$PN"BY13"87;
"MHB_DATA20"
$PN"CV13"124;
"MHB_DATA31"
$PN"DF14"105;
"MH_RESET_L"
$PN"AU14"24;
"MH_ALERT_L"
$PN"AT14"13;
%"TAP"
"1","(-3325,5975)","0","mstr_standard","I162";
;
CDS_LIB"mstr_standard"
BODY_TYPE"PLUMBING"
HDL_TAP"TRUE";
"B \NAC \NWC"1;
"S \NAC"
BN"0"157;
%"TAP"
"1","(-3325,5925)","0","mstr_standard","I163";
;
CDS_LIB"mstr_standard"
BODY_TYPE"PLUMBING"
HDL_TAP"TRUE";
"B \NAC \NWC"1;
"S \NAC"
BN"1"156;
%"TAP"
"1","(-3325,5875)","0","mstr_standard","I164";
;
CDS_LIB"mstr_standard"
BODY_TYPE"PLUMBING"
HDL_TAP"TRUE";
"B \NAC \NWC"1;
"S \NAC"
BN"2"155;
%"TAP"
"1","(-3325,5825)","0","mstr_standard","I165";
;
CDS_LIB"mstr_standard"
BODY_TYPE"PLUMBING"
HDL_TAP"TRUE";
"B \NAC \NWC"1;
"S \NAC"
BN"3"154;
%"TAP"
"1","(-3325,5775)","0","mstr_standard","I166";
;
CDS_LIB"mstr_standard"
BODY_TYPE"PLUMBING"
HDL_TAP"TRUE";
"B \NAC \NWC"1;
"S \NAC"
BN"4"153;
%"TAP"
"1","(-3325,5675)","0","mstr_standard","I167";
;
CDS_LIB"mstr_standard"
BODY_TYPE"PLUMBING"
HDL_TAP"TRUE";
"B \NAC \NWC"1;
"S \NAC"
BN"6"151;
%"TAP"
"1","(-3325,5725)","0","mstr_standard","I168";
;
CDS_LIB"mstr_standard"
BODY_TYPE"PLUMBING"
HDL_TAP"TRUE";
"B \NAC \NWC"1;
"S \NAC"
BN"5"152;
%"TAP"
"1","(-3325,5425)","0","mstr_standard","I169";
;
CDS_LIB"mstr_standard"
BODY_TYPE"PLUMBING"
HDL_TAP"TRUE";
"B \NAC \NWC"1;
"S \NAC"
BN"10"150;
%"TAP"
"1","(-3325,5525)","0","mstr_standard","I170";
;
CDS_LIB"mstr_standard"
BODY_TYPE"PLUMBING"
HDL_TAP"TRUE";
"B \NAC \NWC"1;
"S \NAC"
BN"8"147;
%"TAP"
"1","(-3325,5625)","0","mstr_standard","I171";
;
CDS_LIB"mstr_standard"
BODY_TYPE"PLUMBING"
HDL_TAP"TRUE";
"B \NAC \NWC"1;
"S \NAC"
BN"7"149;
%"TAP"
"1","(-3325,5475)","0","mstr_standard","I172";
;
CDS_LIB"mstr_standard"
BODY_TYPE"PLUMBING"
HDL_TAP"TRUE";
"B \NAC \NWC"1;
"S \NAC"
BN"9"145;
%"TAP"
"1","(-3325,5225)","0","mstr_standard","I173";
;
CDS_LIB"mstr_standard"
BODY_TYPE"PLUMBING"
HDL_TAP"TRUE";
"B \NAC \NWC"1;
"S \NAC"
BN"14"143;
%"TAP"
"1","(-3325,5175)","0","mstr_standard","I174";
;
CDS_LIB"mstr_standard"
BODY_TYPE"PLUMBING"
HDL_TAP"TRUE";
"B \NAC \NWC"1;
"S \NAC"
BN"15"158;
%"TAP"
"1","(-3325,5275)","0","mstr_standard","I175";
;
CDS_LIB"mstr_standard"
BODY_TYPE"PLUMBING"
HDL_TAP"TRUE";
"B \NAC \NWC"1;
"S \NAC"
BN"13"144;
%"TAP"
"1","(-3325,5325)","0","mstr_standard","I176";
;
CDS_LIB"mstr_standard"
BODY_TYPE"PLUMBING"
HDL_TAP"TRUE";
"B \NAC \NWC"1;
"S \NAC"
BN"12"146;
%"TAP"
"1","(-3325,5375)","0","mstr_standard","I177";
;
CDS_LIB"mstr_standard"
BODY_TYPE"PLUMBING"
HDL_TAP"TRUE";
"B \NAC \NWC"1;
"S \NAC"
BN"11"148;
%"TAP"
"1","(-3325,4975)","0","mstr_standard","I178";
;
CDS_LIB"mstr_standard"
BODY_TYPE"PLUMBING"
HDL_TAP"TRUE";
"B \NAC \NWC"1;
"S \NAC"
BN"18"136;
%"TAP"
"1","(-3325,4925)","0","mstr_standard","I179";
;
CDS_LIB"mstr_standard"
BODY_TYPE"PLUMBING"
HDL_TAP"TRUE";
"B \NAC \NWC"1;
"S \NAC"
BN"19"135;
%"TAP"
"1","(-3325,4875)","0","mstr_standard","I180";
;
CDS_LIB"mstr_standard"
BODY_TYPE"PLUMBING"
HDL_TAP"TRUE";
"B \NAC \NWC"1;
"S \NAC"
BN"20"130;
%"TAP"
"1","(-3325,5025)","0","mstr_standard","I181";
;
CDS_LIB"mstr_standard"
BODY_TYPE"PLUMBING"
HDL_TAP"TRUE";
"B \NAC \NWC"1;
"S \NAC"
BN"17"138;
%"TAP"
"1","(-3325,5075)","0","mstr_standard","I182";
;
CDS_LIB"mstr_standard"
BODY_TYPE"PLUMBING"
HDL_TAP"TRUE";
"B \NAC \NWC"1;
"S \NAC"
BN"16"140;
%"TAP"
"1","(-3325,4625)","0","mstr_standard","I183";
;
CDS_LIB"mstr_standard"
BODY_TYPE"PLUMBING"
HDL_TAP"TRUE";
"B \NAC \NWC"1;
"S \NAC"
BN"24"126;
%"TAP"
"1","(-3325,4725)","0","mstr_standard","I184";
;
CDS_LIB"mstr_standard"
BODY_TYPE"PLUMBING"
HDL_TAP"TRUE";
"B \NAC \NWC"1;
"S \NAC"
BN"23"127;
%"TAP"
"1","(-3325,4775)","0","mstr_standard","I185";
;
CDS_LIB"mstr_standard"
BODY_TYPE"PLUMBING"
HDL_TAP"TRUE";
"B \NAC \NWC"1;
"S \NAC"
BN"22"128;
%"TAP"
"1","(-3325,4825)","0","mstr_standard","I186";
;
CDS_LIB"mstr_standard"
BODY_TYPE"PLUMBING"
HDL_TAP"TRUE";
"B \NAC \NWC"1;
"S \NAC"
BN"21"129;
%"TAP"
"1","(-3325,4475)","0","mstr_standard","I187";
;
CDS_LIB"mstr_standard"
BODY_TYPE"PLUMBING"
HDL_TAP"TRUE";
"B \NAC \NWC"1;
"S \NAC"
BN"27"141;
%"TAP"
"1","(-3325,4425)","0","mstr_standard","I188";
;
CDS_LIB"mstr_standard"
BODY_TYPE"PLUMBING"
HDL_TAP"TRUE";
"B \NAC \NWC"1;
"S \NAC"
BN"28"139;
%"TAP"
"1","(-3325,4375)","0","mstr_standard","I189";
;
CDS_LIB"mstr_standard"
BODY_TYPE"PLUMBING"
HDL_TAP"TRUE";
"B \NAC \NWC"1;
"S \NAC"
BN"29"137;
%"TAP"
"1","(-3325,4575)","0","mstr_standard","I190";
;
CDS_LIB"mstr_standard"
BODY_TYPE"PLUMBING"
HDL_TAP"TRUE";
"B \NAC \NWC"1;
"S \NAC"
BN"25"125;
%"TAP"
"1","(-3325,4525)","0","mstr_standard","I191";
;
CDS_LIB"mstr_standard"
BODY_TYPE"PLUMBING"
HDL_TAP"TRUE";
"B \NAC \NWC"1;
"S \NAC"
BN"26"142;
%"TAP"
"1","(-3325,4175)","0","mstr_standard","I192";
;
CDS_LIB"mstr_standard"
BODY_TYPE"PLUMBING"
HDL_TAP"TRUE";
"B \NAC \NWC"2;
"S \NAC"
BN"0"134;
%"TAP"
"1","(-3325,4125)","0","mstr_standard","I193";
;
CDS_LIB"mstr_standard"
BODY_TYPE"PLUMBING"
HDL_TAP"TRUE";
"B \NAC \NWC"2;
"S \NAC"
BN"1"133;
%"TAP"
"1","(-3325,4275)","0","mstr_standard","I194";
;
CDS_LIB"mstr_standard"
BODY_TYPE"PLUMBING"
HDL_TAP"TRUE";
"B \NAC \NWC"1;
"S \NAC"
BN"31"131;
%"TAP"
"1","(-3325,4325)","0","mstr_standard","I195";
;
CDS_LIB"mstr_standard"
BODY_TYPE"PLUMBING"
HDL_TAP"TRUE";
"B \NAC \NWC"1;
"S \NAC"
BN"30"132;
%"TAP"
"1","(-3325,4075)","0","mstr_standard","I197";
;
CDS_LIB"mstr_standard"
BODY_TYPE"PLUMBING"
HDL_TAP"TRUE";
"B \NAC \NWC"2;
"S \NAC"
BN"2"116;
%"TAP"
"1","(-3325,4025)","0","mstr_standard","I198";
;
CDS_LIB"mstr_standard"
BODY_TYPE"PLUMBING"
HDL_TAP"TRUE";
"B \NAC \NWC"2;
"S \NAC"
BN"3"114;
%"TAP"
"1","(-3325,3975)","0","mstr_standard","I199";
;
CDS_LIB"mstr_standard"
BODY_TYPE"PLUMBING"
HDL_TAP"TRUE";
"B \NAC \NWC"2;
"S \NAC"
BN"4"112;
%"TAP"
"1","(-3325,3875)","0","mstr_standard","I200";
;
CDS_LIB"mstr_standard"
BODY_TYPE"PLUMBING"
HDL_TAP"TRUE";
"B \NAC \NWC"2;
"S \NAC"
BN"6"109;
%"TAP"
"1","(-3325,3925)","0","mstr_standard","I201";
;
CDS_LIB"mstr_standard"
BODY_TYPE"PLUMBING"
HDL_TAP"TRUE";
"B \NAC \NWC"2;
"S \NAC"
BN"5"110;
%"TAP"
"1","(-3325,3675)","0","mstr_standard","I202";
;
CDS_LIB"mstr_standard"
BODY_TYPE"PLUMBING"
HDL_TAP"TRUE";
"B \NAC \NWC"2;
"S \NAC"
BN"9"106;
%"TAP"
"1","(-3325,3725)","0","mstr_standard","I203";
;
CDS_LIB"mstr_standard"
BODY_TYPE"PLUMBING"
HDL_TAP"TRUE";
"B \NAC \NWC"2;
"S \NAC"
BN"8"107;
%"TAP"
"1","(-3325,3825)","0","mstr_standard","I204";
;
CDS_LIB"mstr_standard"
BODY_TYPE"PLUMBING"
HDL_TAP"TRUE";
"B \NAC \NWC"2;
"S \NAC"
BN"7"108;
%"TAP"
"1","(-3325,3625)","0","mstr_standard","I205";
;
CDS_LIB"mstr_standard"
BODY_TYPE"PLUMBING"
HDL_TAP"TRUE";
"B \NAC \NWC"2;
"S \NAC"
BN"10"123;
%"TAP"
"1","(-3325,3375)","0","mstr_standard","I206";
;
CDS_LIB"mstr_standard"
BODY_TYPE"PLUMBING"
HDL_TAP"TRUE";
"B \NAC \NWC"2;
"S \NAC"
BN"15"118;
%"TAP"
"1","(-3325,3425)","0","mstr_standard","I207";
;
CDS_LIB"mstr_standard"
BODY_TYPE"PLUMBING"
HDL_TAP"TRUE";
"B \NAC \NWC"2;
"S \NAC"
BN"14"119;
%"TAP"
"1","(-3325,3475)","0","mstr_standard","I208";
;
CDS_LIB"mstr_standard"
BODY_TYPE"PLUMBING"
HDL_TAP"TRUE";
"B \NAC \NWC"2;
"S \NAC"
BN"13"120;
%"TAP"
"1","(-3325,3525)","0","mstr_standard","I209";
;
CDS_LIB"mstr_standard"
BODY_TYPE"PLUMBING"
HDL_TAP"TRUE";
"B \NAC \NWC"2;
"S \NAC"
BN"12"121;
%"TAP"
"1","(-3325,3575)","0","mstr_standard","I210";
;
CDS_LIB"mstr_standard"
BODY_TYPE"PLUMBING"
HDL_TAP"TRUE";
"B \NAC \NWC"2;
"S \NAC"
BN"11"122;
%"TAP"
"1","(-3325,3175)","0","mstr_standard","I211";
;
CDS_LIB"mstr_standard"
BODY_TYPE"PLUMBING"
HDL_TAP"TRUE";
"B \NAC \NWC"2;
"S \NAC"
BN"18"113;
%"TAP"
"1","(-3325,3125)","0","mstr_standard","I212";
;
CDS_LIB"mstr_standard"
BODY_TYPE"PLUMBING"
HDL_TAP"TRUE";
"B \NAC \NWC"2;
"S \NAC"
BN"19"111;
%"TAP"
"1","(-3325,3075)","0","mstr_standard","I213";
;
CDS_LIB"mstr_standard"
BODY_TYPE"PLUMBING"
HDL_TAP"TRUE";
"B \NAC \NWC"2;
"S \NAC"
BN"20"124;
%"TAP"
"1","(-3325,3275)","0","mstr_standard","I214";
;
CDS_LIB"mstr_standard"
BODY_TYPE"PLUMBING"
HDL_TAP"TRUE";
"B \NAC \NWC"2;
"S \NAC"
BN"16"117;
%"TAP"
"1","(-3325,3225)","0","mstr_standard","I215";
;
CDS_LIB"mstr_standard"
BODY_TYPE"PLUMBING"
HDL_TAP"TRUE";
"B \NAC \NWC"2;
"S \NAC"
BN"17"115;
%"TAP"
"1","(-3325,2975)","0","mstr_standard","I216";
;
CDS_LIB"mstr_standard"
BODY_TYPE"PLUMBING"
HDL_TAP"TRUE";
"B \NAC \NWC"2;
"S \NAC"
BN"22"102;
%"TAP"
"1","(-3325,2925)","0","mstr_standard","I217";
;
CDS_LIB"mstr_standard"
BODY_TYPE"PLUMBING"
HDL_TAP"TRUE";
"B \NAC \NWC"2;
"S \NAC"
BN"23"101;
%"TAP"
"1","(-3325,3025)","0","mstr_standard","I218";
;
CDS_LIB"mstr_standard"
BODY_TYPE"PLUMBING"
HDL_TAP"TRUE";
"B \NAC \NWC"2;
"S \NAC"
BN"21"103;
%"TAP"
"1","(-3325,2825)","0","mstr_standard","I219";
;
CDS_LIB"mstr_standard"
BODY_TYPE"PLUMBING"
HDL_TAP"TRUE";
"B \NAC \NWC"2;
"S \NAC"
BN"24"100;
%"TAP"
"1","(-3325,2675)","0","mstr_standard","I220";
;
CDS_LIB"mstr_standard"
BODY_TYPE"PLUMBING"
HDL_TAP"TRUE";
"B \NAC \NWC"2;
"S \NAC"
BN"27"97;
%"TAP"
"1","(-3325,2625)","0","mstr_standard","I221";
;
CDS_LIB"mstr_standard"
BODY_TYPE"PLUMBING"
HDL_TAP"TRUE";
"B \NAC \NWC"2;
"S \NAC"
BN"28"96;
%"TAP"
"1","(-3325,2575)","0","mstr_standard","I222";
;
CDS_LIB"mstr_standard"
BODY_TYPE"PLUMBING"
HDL_TAP"TRUE";
"B \NAC \NWC"2;
"S \NAC"
BN"29"95;
%"TAP"
"1","(-3325,2775)","0","mstr_standard","I223";
;
CDS_LIB"mstr_standard"
BODY_TYPE"PLUMBING"
HDL_TAP"TRUE";
"B \NAC \NWC"2;
"S \NAC"
BN"25"99;
%"TAP"
"1","(-3325,2725)","0","mstr_standard","I224";
;
CDS_LIB"mstr_standard"
BODY_TYPE"PLUMBING"
HDL_TAP"TRUE";
"B \NAC \NWC"2;
"S \NAC"
BN"26"98;
%"TAP"
"1","(-3325,2375)","0","mstr_standard","I225";
;
CDS_LIB"mstr_standard"
BODY_TYPE"PLUMBING"
HDL_TAP"TRUE";
"B \NAC \NWC"3;
"S \NAC"
BN"0"94;
%"TAP"
"1","(-3325,2325)","0","mstr_standard","I226";
;
CDS_LIB"mstr_standard"
BODY_TYPE"PLUMBING"
HDL_TAP"TRUE";
"B \NAC \NWC"3;
"S \NAC"
BN"1"93;
%"TAP"
"1","(-3325,2525)","0","mstr_standard","I227";
;
CDS_LIB"mstr_standard"
BODY_TYPE"PLUMBING"
HDL_TAP"TRUE";
"B \NAC \NWC"2;
"S \NAC"
BN"30"89;
%"TAP"
"1","(-3325,2475)","0","mstr_standard","I228";
;
CDS_LIB"mstr_standard"
BODY_TYPE"PLUMBING"
HDL_TAP"TRUE";
"B \NAC \NWC"2;
"S \NAC"
BN"31"105;
%"TAP"
"1","(-3325,2225)","0","mstr_standard","I229";
;
CDS_LIB"mstr_standard"
BODY_TYPE"PLUMBING"
HDL_TAP"TRUE";
"B \NAC \NWC"3;
"S \NAC"
BN"3"91;
%"TAP"
"1","(-3325,2275)","0","mstr_standard","I230";
;
CDS_LIB"mstr_standard"
BODY_TYPE"PLUMBING"
HDL_TAP"TRUE";
"B \NAC \NWC"3;
"S \NAC"
BN"2"92;
%"TAP"
"1","(-3325,2075)","0","mstr_standard","I231";
;
CDS_LIB"mstr_standard"
BODY_TYPE"PLUMBING"
HDL_TAP"TRUE";
"B \NAC \NWC"3;
"S \NAC"
BN"6"104;
%"TAP"
"1","(-3325,2125)","0","mstr_standard","I232";
;
CDS_LIB"mstr_standard"
BODY_TYPE"PLUMBING"
HDL_TAP"TRUE";
"B \NAC \NWC"3;
"S \NAC"
BN"5"88;
%"TAP"
"1","(-3325,2175)","0","mstr_standard","I233";
;
CDS_LIB"mstr_standard"
BODY_TYPE"PLUMBING"
HDL_TAP"TRUE";
"B \NAC \NWC"3;
"S \NAC"
BN"4"90;
%"TAP"
"1","(-3325,1875)","0","mstr_standard","I235";
;
CDS_LIB"mstr_standard"
BODY_TYPE"PLUMBING"
HDL_TAP"TRUE";
"B \NAC \NWC"4;
"S \NAC"
BN"1"86;
%"TAP"
"1","(-3325,1925)","0","mstr_standard","I236";
;
CDS_LIB"mstr_standard"
BODY_TYPE"PLUMBING"
HDL_TAP"TRUE";
"B \NAC \NWC"4;
"S \NAC"
BN"0"87;
%"TAP"
"1","(-3325,2025)","0","mstr_standard","I237";
;
CDS_LIB"mstr_standard"
BODY_TYPE"PLUMBING"
HDL_TAP"TRUE";
"B \NAC \NWC"3;
"S \NAC"
BN"7"85;
%"TAP"
"1","(-3325,1825)","0","mstr_standard","I238";
;
CDS_LIB"mstr_standard"
BODY_TYPE"PLUMBING"
HDL_TAP"TRUE";
"B \NAC \NWC"4;
"S \NAC"
BN"2"84;
%"TAP"
"1","(-3325,1775)","0","mstr_standard","I239";
;
CDS_LIB"mstr_standard"
BODY_TYPE"PLUMBING"
HDL_TAP"TRUE";
"B \NAC \NWC"4;
"S \NAC"
BN"3"83;
%"TAP"
"1","(-3325,1725)","0","mstr_standard","I240";
;
CDS_LIB"mstr_standard"
BODY_TYPE"PLUMBING"
HDL_TAP"TRUE";
"B \NAC \NWC"4;
"S \NAC"
BN"4"82;
%"TAP"
"1","(-3325,1675)","0","mstr_standard","I241";
;
CDS_LIB"mstr_standard"
BODY_TYPE"PLUMBING"
HDL_TAP"TRUE";
"B \NAC \NWC"4;
"S \NAC"
BN"5"81;
%"TAP"
"1","(-3325,1575)","0","mstr_standard","I242";
;
CDS_LIB"mstr_standard"
BODY_TYPE"PLUMBING"
HDL_TAP"TRUE";
"B \NAC \NWC"4;
"S \NAC"
BN"7"79;
%"TAP"
"1","(-3325,1625)","0","mstr_standard","I243";
;
CDS_LIB"mstr_standard"
BODY_TYPE"PLUMBING"
HDL_TAP"TRUE";
"B \NAC \NWC"4;
"S \NAC"
BN"6"80;
%"TAP"
"1","(-5750,5975)","2","mstr_standard","I244";
;
CDS_LIB"mstr_standard"
BODY_TYPE"PLUMBING"
HDL_TAP"TRUE";
"B \NAC \NWC"5;
"S \NAC"
BN"0"75;
%"TAP"
"1","(-5750,5775)","2","mstr_standard","I245";
;
CDS_LIB"mstr_standard"
BODY_TYPE"PLUMBING"
HDL_TAP"TRUE";
"B \NAC \NWC"5;
"S \NAC"
BN"2"71;
%"TAP"
"1","(-5750,5875)","2","mstr_standard","I246";
;
CDS_LIB"mstr_standard"
BODY_TYPE"PLUMBING"
HDL_TAP"TRUE";
"B \NAC \NWC"5;
"S \NAC"
BN"1"73;
%"TAP"
"1","(-5750,5675)","2","mstr_standard","I247";
;
CDS_LIB"mstr_standard"
BODY_TYPE"PLUMBING"
HDL_TAP"TRUE";
"B \NAC \NWC"5;
"S \NAC"
BN"3"69;
%"TAP"
"1","(-5950,5925)","2","mstr_standard","I248";
;
CDS_LIB"mstr_standard"
BODY_TYPE"PLUMBING"
HDL_TAP"TRUE";
"B \NAC \NWC"9;
"S \NAC"
BN"0"62;
%"TAP"
"1","(-5950,5825)","2","mstr_standard","I249";
;
CDS_LIB"mstr_standard"
BODY_TYPE"PLUMBING"
HDL_TAP"TRUE";
"B \NAC \NWC"9;
"S \NAC"
BN"1"61;
%"TAP"
"1","(-5950,5725)","2","mstr_standard","I250";
;
CDS_LIB"mstr_standard"
BODY_TYPE"PLUMBING"
HDL_TAP"TRUE";
"B \NAC \NWC"9;
"S \NAC"
BN"2"78;
%"TAP"
"1","(-5750,5575)","2","mstr_standard","I251";
;
CDS_LIB"mstr_standard"
BODY_TYPE"PLUMBING"
HDL_TAP"TRUE";
"B \NAC \NWC"5;
"S \NAC"
BN"4"67;
%"TAP"
"1","(-5750,5475)","2","mstr_standard","I252";
;
CDS_LIB"mstr_standard"
BODY_TYPE"PLUMBING"
HDL_TAP"TRUE";
"B \NAC \NWC"5;
"S \NAC"
BN"5"66;
%"TAP"
"1","(-5950,5625)","2","mstr_standard","I253";
;
CDS_LIB"mstr_standard"
BODY_TYPE"PLUMBING"
HDL_TAP"TRUE";
"B \NAC \NWC"9;
"S \NAC"
BN"3"77;
%"TAP"
"1","(-5750,5375)","2","mstr_standard","I254";
;
CDS_LIB"mstr_standard"
BODY_TYPE"PLUMBING"
HDL_TAP"TRUE";
"B \NAC \NWC"5;
"S \NAC"
BN"6"65;
%"TAP"
"1","(-5750,5275)","2","mstr_standard","I255";
;
CDS_LIB"mstr_standard"
BODY_TYPE"PLUMBING"
HDL_TAP"TRUE";
"B \NAC \NWC"5;
"S \NAC"
BN"7"64;
%"TAP"
"1","(-5750,5175)","2","mstr_standard","I256";
;
CDS_LIB"mstr_standard"
BODY_TYPE"PLUMBING"
HDL_TAP"TRUE";
"B \NAC \NWC"5;
"S \NAC"
BN"8"63;
%"TAP"
"1","(-5950,5525)","2","mstr_standard","I257";
;
CDS_LIB"mstr_standard"
BODY_TYPE"PLUMBING"
HDL_TAP"TRUE";
"B \NAC \NWC"9;
"S \NAC"
BN"4"76;
%"TAP"
"1","(-5950,5425)","2","mstr_standard","I258";
;
CDS_LIB"mstr_standard"
BODY_TYPE"PLUMBING"
HDL_TAP"TRUE";
"B \NAC \NWC"9;
"S \NAC"
BN"5"74;
%"TAP"
"1","(-5950,5325)","2","mstr_standard","I259";
;
CDS_LIB"mstr_standard"
BODY_TYPE"PLUMBING"
HDL_TAP"TRUE";
"B \NAC \NWC"9;
"S \NAC"
BN"6"72;
%"TAP"
"1","(-5950,5125)","2","mstr_standard","I260";
;
CDS_LIB"mstr_standard"
BODY_TYPE"PLUMBING"
HDL_TAP"TRUE";
"B \NAC \NWC"9;
"S \NAC"
BN"8"68;
%"TAP"
"1","(-5950,5225)","2","mstr_standard","I261";
;
CDS_LIB"mstr_standard"
BODY_TYPE"PLUMBING"
HDL_TAP"TRUE";
"B \NAC \NWC"9;
"S \NAC"
BN"7"70;
%"TAP"
"1","(-5750,5075)","2","mstr_standard","I262";
;
CDS_LIB"mstr_standard"
BODY_TYPE"PLUMBING"
HDL_TAP"TRUE";
"B \NAC \NWC"5;
"S \NAC"
BN"9"47;
%"TAP"
"1","(-5750,4925)","2","mstr_standard","I263";
;
CDS_LIB"mstr_standard"
BODY_TYPE"PLUMBING"
HDL_TAP"TRUE";
"B \NAC \NWC"6;
"S \NAC"
BN"0"54;
%"TAP"
"1","(-5750,4825)","2","mstr_standard","I264";
;
CDS_LIB"mstr_standard"
BODY_TYPE"PLUMBING"
HDL_TAP"TRUE";
"B \NAC \NWC"6;
"S \NAC"
BN"1"52;
%"TAP"
"1","(-5750,4725)","2","mstr_standard","I265";
;
CDS_LIB"mstr_standard"
BODY_TYPE"PLUMBING"
HDL_TAP"TRUE";
"B \NAC \NWC"6;
"S \NAC"
BN"2"50;
%"TAP"
"1","(-5750,4625)","2","mstr_standard","I266";
;
CDS_LIB"mstr_standard"
BODY_TYPE"PLUMBING"
HDL_TAP"TRUE";
"B \NAC \NWC"6;
"S \NAC"
BN"3"48;
%"TAP"
"1","(-5950,5025)","2","mstr_standard","I267";
;
CDS_LIB"mstr_standard"
BODY_TYPE"PLUMBING"
HDL_TAP"TRUE";
"B \NAC \NWC"9;
"S \NAC"
BN"9"56;
%"TAP"
"1","(-5950,4875)","2","mstr_standard","I268";
;
CDS_LIB"mstr_standard"
BODY_TYPE"PLUMBING"
HDL_TAP"TRUE";
"B \NAC \NWC"10;
"S \NAC"
BN"0"60;
%"TAP"
"1","(-5950,4775)","2","mstr_standard","I269";
;
CDS_LIB"mstr_standard"
BODY_TYPE"PLUMBING"
HDL_TAP"TRUE";
"B \NAC \NWC"10;
"S \NAC"
BN"1"59;
%"TAP"
"1","(-5950,4675)","2","mstr_standard","I270";
;
CDS_LIB"mstr_standard"
BODY_TYPE"PLUMBING"
HDL_TAP"TRUE";
"B \NAC \NWC"10;
"S \NAC"
BN"2"58;
%"TAP"
"1","(-5750,4525)","2","mstr_standard","I271";
;
CDS_LIB"mstr_standard"
BODY_TYPE"PLUMBING"
HDL_TAP"TRUE";
"B \NAC \NWC"6;
"S \NAC"
BN"4"46;
%"TAP"
"1","(-5750,4425)","2","mstr_standard","I272";
;
CDS_LIB"mstr_standard"
BODY_TYPE"PLUMBING"
HDL_TAP"TRUE";
"B \NAC \NWC"6;
"S \NAC"
BN"5"45;
%"TAP"
"1","(-5750,4325)","2","mstr_standard","I273";
;
CDS_LIB"mstr_standard"
BODY_TYPE"PLUMBING"
HDL_TAP"TRUE";
"B \NAC \NWC"6;
"S \NAC"
BN"6"44;
%"TAP"
"1","(-5750,4225)","2","mstr_standard","I274";
;
CDS_LIB"mstr_standard"
BODY_TYPE"PLUMBING"
HDL_TAP"TRUE";
"B \NAC \NWC"6;
"S \NAC"
BN"7"43;
%"TAP"
"1","(-5750,4125)","2","mstr_standard","I275";
;
CDS_LIB"mstr_standard"
BODY_TYPE"PLUMBING"
HDL_TAP"TRUE";
"B \NAC \NWC"6;
"S \NAC"
BN"8"42;
%"TAP"
"1","(-5950,4575)","2","mstr_standard","I276";
;
CDS_LIB"mstr_standard"
BODY_TYPE"PLUMBING"
HDL_TAP"TRUE";
"B \NAC \NWC"10;
"S \NAC"
BN"3"57;
%"TAP"
"1","(-5950,4475)","2","mstr_standard","I277";
;
CDS_LIB"mstr_standard"
BODY_TYPE"PLUMBING"
HDL_TAP"TRUE";
"B \NAC \NWC"10;
"S \NAC"
BN"4"55;
%"TAP"
"1","(-5950,4375)","2","mstr_standard","I278";
;
CDS_LIB"mstr_standard"
BODY_TYPE"PLUMBING"
HDL_TAP"TRUE";
"B \NAC \NWC"10;
"S \NAC"
BN"5"53;
%"TAP"
"1","(-5950,4275)","2","mstr_standard","I279";
;
CDS_LIB"mstr_standard"
BODY_TYPE"PLUMBING"
HDL_TAP"TRUE";
"B \NAC \NWC"10;
"S \NAC"
BN"6"51;
%"TAP"
"1","(-5950,4175)","2","mstr_standard","I280";
;
CDS_LIB"mstr_standard"
BODY_TYPE"PLUMBING"
HDL_TAP"TRUE";
"B \NAC \NWC"10;
"S \NAC"
BN"7"49;
%"TAP"
"1","(-5750,4025)","2","mstr_standard","I285";
;
CDS_LIB"mstr_standard"
BODY_TYPE"PLUMBING"
HDL_TAP"TRUE";
"B \NAC \NWC"6;
"S \NAC"
BN"9"25;
%"TAP"
"1","(-5950,4075)","2","mstr_standard","I286";
;
CDS_LIB"mstr_standard"
BODY_TYPE"PLUMBING"
HDL_TAP"TRUE";
"B \NAC \NWC"10;
"S \NAC"
BN"8"27;
%"TAP"
"1","(-5950,3975)","2","mstr_standard","I287";
;
CDS_LIB"mstr_standard"
BODY_TYPE"PLUMBING"
HDL_TAP"TRUE";
"B \NAC \NWC"10;
"S \NAC"
BN"9"26;
%"TAP"
"1","(-5950,3825)","2","mstr_standard","I288";
;
CDS_LIB"mstr_standard"
BODY_TYPE"PLUMBING"
HDL_TAP"TRUE";
"B \NAC \NWC"7;
"S \NAC"
BN"0"41;
%"TAP"
"1","(-5950,3775)","2","mstr_standard","I289";
;
CDS_LIB"mstr_standard"
BODY_TYPE"PLUMBING"
HDL_TAP"TRUE";
"B \NAC \NWC"7;
"S \NAC"
BN"1"39;
%"TAP"
"1","(-5950,3725)","2","mstr_standard","I290";
;
CDS_LIB"mstr_standard"
BODY_TYPE"PLUMBING"
HDL_TAP"TRUE";
"B \NAC \NWC"7;
"S \NAC"
BN"2"37;
%"TAP"
"1","(-5950,3675)","2","mstr_standard","I291";
;
CDS_LIB"mstr_standard"
BODY_TYPE"PLUMBING"
HDL_TAP"TRUE";
"B \NAC \NWC"7;
"S \NAC"
BN"3"35;
%"TAP"
"1","(-5950,3625)","2","mstr_standard","I292";
;
CDS_LIB"mstr_standard"
BODY_TYPE"PLUMBING"
HDL_TAP"TRUE";
"B \NAC \NWC"7;
"S \NAC"
BN"4"33;
%"TAP"
"1","(-5950,3575)","2","mstr_standard","I293";
;
CDS_LIB"mstr_standard"
BODY_TYPE"PLUMBING"
HDL_TAP"TRUE";
"B \NAC \NWC"7;
"S \NAC"
BN"5"31;
%"TAP"
"1","(-5950,3525)","2","mstr_standard","I294";
;
CDS_LIB"mstr_standard"
BODY_TYPE"PLUMBING"
HDL_TAP"TRUE";
"B \NAC \NWC"7;
"S \NAC"
BN"6"29;
%"TAP"
"1","(-5950,3325)","2","mstr_standard","I295";
;
CDS_LIB"mstr_standard"
BODY_TYPE"PLUMBING"
HDL_TAP"TRUE";
"B \NAC \NWC"8;
"S \NAC"
BN"2"36;
%"TAP"
"1","(-5950,3425)","2","mstr_standard","I296";
;
CDS_LIB"mstr_standard"
BODY_TYPE"PLUMBING"
HDL_TAP"TRUE";
"B \NAC \NWC"8;
"S \NAC"
BN"0"40;
%"TAP"
"1","(-5950,3375)","2","mstr_standard","I297";
;
CDS_LIB"mstr_standard"
BODY_TYPE"PLUMBING"
HDL_TAP"TRUE";
"B \NAC \NWC"8;
"S \NAC"
BN"1"38;
%"TAP"
"1","(-5950,3275)","2","mstr_standard","I298";
;
CDS_LIB"mstr_standard"
BODY_TYPE"PLUMBING"
HDL_TAP"TRUE";
"B \NAC \NWC"8;
"S \NAC"
BN"3"34;
%"TAP"
"1","(-5950,3225)","2","mstr_standard","I299";
;
CDS_LIB"mstr_standard"
BODY_TYPE"PLUMBING"
HDL_TAP"TRUE";
"B \NAC \NWC"8;
"S \NAC"
BN"4"32;
%"TAP"
"1","(-5950,3125)","2","mstr_standard","I300";
;
CDS_LIB"mstr_standard"
BODY_TYPE"PLUMBING"
HDL_TAP"TRUE";
"B \NAC \NWC"8;
"S \NAC"
BN"6"28;
%"TAP"
"1","(-5950,3175)","2","mstr_standard","I301";
;
CDS_LIB"mstr_standard"
BODY_TYPE"PLUMBING"
HDL_TAP"TRUE";
"B \NAC \NWC"8;
"S \NAC"
BN"5"30;
%"Q_RES"
"1","(-6875,2125)","0","pure_quanta","I314";
;
LOCATION"R382"
$SEC"1"
CDS_SEC"1"
TOLERANCE"1%"
VALUE"15   "
PART_NUMBER"CS01502FB11"
PACK_TYPE"0402LF"
CDS_LIB"pure_quanta"
WATTAGE"1/16W"
MATERIAL"CHIP";
"B"
$PN"2"13;
"A"
$PN"1"11;
END.
